(kicad_pcb
	(version 20260206)
	(generator "pcbnew")
	(generator_version "10.0")
	(general
		(thickness 1.6)
		(legacy_teardrops no)
	)
	(paper "A4")
	(title_block
		(title "03242023_DA0F0TMBIJ0_F0T_Motherboard_J_brd_V01_OCP.brd")
		(comment 1 "Grand Teton / footprints 933-940 of 6105")
	)
	(layers
		(0 "F.Cu" signal "TOP")
		(4 "In1.Cu" signal "GND")
		(6 "In2.Cu" signal "IN1")
		(8 "In3.Cu" signal "GND1")
		(10 "In4.Cu" signal "IN2")
		(12 "In5.Cu" signal "GND2")
		(14 "In6.Cu" signal "IN3")
		(16 "In7.Cu" signal "GND3")
		(18 "In8.Cu" signal "VCC")
		(20 "In9.Cu" signal "VCC1")
		(22 "In10.Cu" signal "GND4")
		(24 "In11.Cu" signal "IN4")
		(26 "In12.Cu" signal "GND5")
		(28 "In13.Cu" signal "IN5")
		(30 "In14.Cu" signal "GND6")
		(32 "In15.Cu" signal "IN6")
		(34 "In16.Cu" signal "GND7")
		(2 "B.Cu" signal "BOTTOM")
		(9 "F.Adhes" user "F.Adhesive")
		(11 "B.Adhes" user "B.Adhesive")
		(13 "F.Paste" user "Package Geometry/Pastemask Top")
		(15 "B.Paste" user "Package Geometry/Pastemask Bottom")
		(5 "F.SilkS" user "Ref Des/Silkscreen Top")
		(7 "B.SilkS" user "Ref Des/Silkscreen Bottom")
		(1 "F.Mask" user "Board Geometry/Soldermask Top")
		(3 "B.Mask" user "Board Geometry/Soldermask Bottom")
		(17 "Dwgs.User" user "User.Drawings")
		(19 "Cmts.User" user "User.Comments")
		(21 "Eco1.User" user "User.Eco1")
		(23 "Eco2.User" user "User.Eco2")
		(25 "Edge.Cuts" user "Board Geometry/Outline")
		(27 "Margin" user)
		(31 "F.CrtYd" user "Package Geometry/Place Bound Top")
		(29 "B.CrtYd" user "Package Geometry/Place Bound Bottom")
		(35 "F.Fab" user "Ref Des/Assembly Top")
		(33 "B.Fab" user "Ref Des/Assembly Bottom")
	)
	(footprint ""
		(layer "F.Cu")
		(at 336.847688 -408.517344 -90)
		(property "Reference" "C923"
			(at 0 0 270)
			(layer "F.SilkS")
			(hide yes)
			(effects
				(font
					(size 1.27 1.27)
				)
			)
		)
		(property "Value" ""
			(at 0 0 270)
			(layer "F.Fab")
			(effects
				(font
					(size 1.27 1.27)
				)
			)
		)
		(duplicate_pad_numbers_are_jumpers no)
		(fp_line
			(start -0.299974 0.150114)
			(end -0.299974 -0.150114)
			(stroke
				(width 0.1)
				(type default)
			)
			(layer "F.Fab")
		)
		(fp_line
			(start 0.299974 0.150114)
			(end -0.299974 0.150114)
			(stroke
				(width 0.1)
				(type default)
			)
			(layer "F.Fab")
		)
		(fp_line
			(start -0.299974 -0.150114)
			(end 0.299974 -0.150114)
			(stroke
				(width 0.1)
				(type default)
			)
			(layer "F.Fab")
		)
		(fp_line
			(start 0.299974 -0.150114)
			(end 0.299974 0.150114)
			(stroke
				(width 0.1)
				(type default)
			)
			(layer "F.Fab")
		)
		(pad "1" smd rect
			(at -0.2667 0 270)
			(size 0.3048 0.381)
			(layers "F.Cu" "F.Mask" "F.Paste")
			(net "P5E_CPU0_PE0_TX_C_DP<5>")
		)
		(pad "2" smd rect
			(at 0.2667 0 270)
			(size 0.3048 0.381)
			(layers "F.Cu" "F.Mask" "F.Paste")
			(net "P5E_CPU0_PE0_TX_DP<5>")
		)
	)
	(footprint ""
		(layer "F.Cu")
		(at 427.634654 -366.691164 -90)
		(property "Reference" "PC1177"
			(at 0 0 270)
			(layer "F.SilkS")
			(hide yes)
			(effects
				(font
					(size 1.27 1.27)
				)
			)
		)
		(property "Value" ""
			(at 0 0 270)
			(layer "F.Fab")
			(effects
				(font
					(size 1.27 1.27)
				)
			)
		)
		(duplicate_pad_numbers_are_jumpers no)
		(fp_line
			(start -0.7874 0.4064)
			(end -0.7874 -0.4064)
			(stroke
				(width 0.1524)
				(type default)
			)
			(layer "F.SilkS")
		)
		(fp_line
			(start 0.7874 0.4064)
			(end -0.7874 0.4064)
			(stroke
				(width 0.1524)
				(type default)
			)
			(layer "F.SilkS")
		)
		(fp_line
			(start -0.7874 -0.4064)
			(end 0.7874 -0.4064)
			(stroke
				(width 0.1524)
				(type default)
			)
			(layer "F.SilkS")
		)
		(fp_line
			(start 0.7874 -0.4064)
			(end 0.7874 0.4064)
			(stroke
				(width 0.1524)
				(type default)
			)
			(layer "F.SilkS")
		)
		(fp_line
			(start -0.67945 0.3048)
			(end -0.67945 -0.305054)
			(stroke
				(width 0.1)
				(type default)
			)
			(layer "F.Fab")
		)
		(fp_line
			(start -0.12065 0.3048)
			(end -0.67945 0.3048)
			(stroke
				(width 0.1)
				(type default)
			)
			(layer "F.Fab")
		)
		(fp_line
			(start 0.120396 0.3048)
			(end 0.120396 0.2794)
			(stroke
				(width 0.1)
				(type default)
			)
			(layer "F.Fab")
		)
		(fp_line
			(start 0.67945 0.3048)
			(end 0.120396 0.3048)
			(stroke
				(width 0.1)
				(type default)
			)
			(layer "F.Fab")
		)
		(fp_line
			(start -0.12065 0.2794)
			(end -0.12065 0.3048)
			(stroke
				(width 0.1)
				(type default)
			)
			(layer "F.Fab")
		)
		(fp_line
			(start 0.120396 0.2794)
			(end -0.12065 0.2794)
			(stroke
				(width 0.1)
				(type default)
			)
			(layer "F.Fab")
		)
		(fp_line
			(start -0.12065 -0.2794)
			(end 0.12065 -0.2794)
			(stroke
				(width 0.1)
				(type default)
			)
			(layer "F.Fab")
		)
		(fp_line
			(start 0.12065 -0.2794)
			(end 0.12065 -0.3048)
			(stroke
				(width 0.1)
				(type default)
			)
			(layer "F.Fab")
		)
		(fp_line
			(start 0.12065 -0.3048)
			(end 0.67945 -0.3048)
			(stroke
				(width 0.1)
				(type default)
			)
			(layer "F.Fab")
		)
		(fp_line
			(start 0.67945 -0.3048)
			(end 0.67945 0.3048)
			(stroke
				(width 0.1)
				(type default)
			)
			(layer "F.Fab")
		)
		(fp_line
			(start -0.67945 -0.305054)
			(end -0.12065 -0.305054)
			(stroke
				(width 0.1)
				(type default)
			)
			(layer "F.Fab")
		)
		(fp_line
			(start -0.12065 -0.305054)
			(end -0.12065 -0.2794)
			(stroke
				(width 0.1)
				(type default)
			)
			(layer "F.Fab")
		)
		(pad "1" smd circle
			(at -0.40005 0 270)
			(size 0 0)
			(layers "F.Cu" "F.Mask" "F.Paste")
			(net "SW_PVCCFA_EHV_FIVRA_CPU0_BOOT3_")
		)
		(pad "2" smd circle
			(at 0.40005 0 270)
			(size 0 0)
			(layers "F.Cu" "F.Mask" "F.Paste")
			(net "SW_PVCCFA_EHV_FIVRA_CPU0_BOOTR3")
		)
	)
	(footprint ""
		(layer "F.Cu")
		(at 183.69788 -130.266948 -90)
		(property "Reference" "R283"
			(at 0 0 270)
			(layer "F.SilkS")
			(hide yes)
			(effects
				(font
					(size 1.27 1.27)
				)
			)
		)
		(property "Value" ""
			(at 0 0 270)
			(layer "F.Fab")
			(effects
				(font
					(size 1.27 1.27)
				)
			)
		)
		(duplicate_pad_numbers_are_jumpers no)
		(fp_line
			(start -0.7874 0.4064)
			(end -0.7874 -0.4064)
			(stroke
				(width 0.1524)
				(type default)
			)
			(layer "F.SilkS")
		)
		(fp_line
			(start 0.7874 0.4064)
			(end -0.7874 0.4064)
			(stroke
				(width 0.1524)
				(type default)
			)
			(layer "F.SilkS")
		)
		(fp_line
			(start -0.7874 -0.4064)
			(end 0.7874 -0.4064)
			(stroke
				(width 0.1524)
				(type default)
			)
			(layer "F.SilkS")
		)
		(fp_line
			(start 0.7874 -0.4064)
			(end 0.7874 0.4064)
			(stroke
				(width 0.1524)
				(type default)
			)
			(layer "F.SilkS")
		)
		(fp_line
			(start -0.67945 0.3048)
			(end -0.67945 -0.305054)
			(stroke
				(width 0.1)
				(type default)
			)
			(layer "F.Fab")
		)
		(fp_line
			(start -0.12065 0.3048)
			(end -0.67945 0.3048)
			(stroke
				(width 0.1)
				(type default)
			)
			(layer "F.Fab")
		)
		(fp_line
			(start 0.120396 0.3048)
			(end 0.120396 0.2794)
			(stroke
				(width 0.1)
				(type default)
			)
			(layer "F.Fab")
		)
		(fp_line
			(start 0.67945 0.3048)
			(end 0.120396 0.3048)
			(stroke
				(width 0.1)
				(type default)
			)
			(layer "F.Fab")
		)
		(fp_line
			(start -0.12065 0.2794)
			(end -0.12065 0.3048)
			(stroke
				(width 0.1)
				(type default)
			)
			(layer "F.Fab")
		)
		(fp_line
			(start 0.120396 0.2794)
			(end -0.12065 0.2794)
			(stroke
				(width 0.1)
				(type default)
			)
			(layer "F.Fab")
		)
		(fp_line
			(start -0.12065 -0.2794)
			(end 0.12065 -0.2794)
			(stroke
				(width 0.1)
				(type default)
			)
			(layer "F.Fab")
		)
		(fp_line
			(start 0.12065 -0.2794)
			(end 0.12065 -0.3048)
			(stroke
				(width 0.1)
				(type default)
			)
			(layer "F.Fab")
		)
		(fp_line
			(start 0.12065 -0.3048)
			(end 0.67945 -0.3048)
			(stroke
				(width 0.1)
				(type default)
			)
			(layer "F.Fab")
		)
		(fp_line
			(start 0.67945 -0.3048)
			(end 0.67945 0.3048)
			(stroke
				(width 0.1)
				(type default)
			)
			(layer "F.Fab")
		)
		(fp_line
			(start -0.67945 -0.305054)
			(end -0.12065 -0.305054)
			(stroke
				(width 0.1)
				(type default)
			)
			(layer "F.Fab")
		)
		(fp_line
			(start -0.12065 -0.305054)
			(end -0.12065 -0.2794)
			(stroke
				(width 0.1)
				(type default)
			)
			(layer "F.Fab")
		)
		(pad "1" smd circle
			(at -0.40005 0 270)
			(size 0 0)
			(layers "F.Cu" "F.Mask" "F.Paste")
			(net "P3V3_AUX")
		)
		(pad "2" smd circle
			(at 0.40005 0 270)
			(size 0 0)
			(layers "F.Cu" "F.Mask" "F.Paste")
			(net "FM_CPU0_PKGID0")
		)
	)
	(footprint ""
		(layer "F.Cu")
		(at 133.420104 -297.514772)
		(property "Reference" "H16"
			(at 0.201676 -6.217666 0)
			(unlocked yes)
			(layer "F.SilkS")
			(effects
				(font
					(size 0.7874 0.5842)
					(thickness 0.1524)
				)
				(justify left)
			)
		)
		(property "Value" ""
			(at 0 0 0)
			(layer "F.Fab")
			(effects
				(font
					(size 1.27 1.27)
				)
			)
		)
		(duplicate_pad_numbers_are_jumpers no)
		(fp_circle
			(center 0 0)
			(end 2.5273 0)
			(stroke
				(width 0.1524)
				(type default)
			)
			(fill no)
			(layer "F.SilkS")
		)
		(fp_circle
			(center 0 0)
			(end 2.5273 0)
			(stroke
				(width 0.1524)
				(type default)
			)
			(fill no)
			(layer "B.SilkS")
		)
		(fp_circle
			(center 0 0)
			(end 2.5273 0)
			(stroke
				(width 0.1)
				(type default)
			)
			(fill no)
			(layer "B.Fab")
		)
		(fp_circle
			(center 0 0)
			(end 2.5273 0)
			(stroke
				(width 0.1)
				(type default)
			)
			(fill no)
			(layer "F.Fab")
		)
		(pad "" np_thru_hole circle
			(at 0 0)
			(size 3.429 3.429)
			(drill 3.429)
			(layers "*.Cu" "*.Mask")
			(clearance 0.381)
			(thermal_gap 0.381)
		)
	)
	(footprint ""
		(layer "F.Cu")
		(at 16.110966 -92.687648 90)
		(property "Reference" "R3658"
			(at 0 0 90)
			(layer "F.SilkS")
			(hide yes)
			(effects
				(font
					(size 1.27 1.27)
				)
			)
		)
		(property "Value" ""
			(at 0 0 90)
			(layer "F.Fab")
			(effects
				(font
					(size 1.27 1.27)
				)
			)
		)
		(duplicate_pad_numbers_are_jumpers no)
		(fp_line
			(start 0.7874 -0.4064)
			(end 0.7874 0.4064)
			(stroke
				(width 0.1524)
				(type default)
			)
			(layer "F.SilkS")
		)
		(fp_line
			(start -0.7874 -0.4064)
			(end 0.7874 -0.4064)
			(stroke
				(width 0.1524)
				(type default)
			)
			(layer "F.SilkS")
		)
		(fp_line
			(start 0.7874 0.4064)
			(end -0.7874 0.4064)
			(stroke
				(width 0.1524)
				(type default)
			)
			(layer "F.SilkS")
		)
		(fp_line
			(start -0.7874 0.4064)
			(end -0.7874 -0.4064)
			(stroke
				(width 0.1524)
				(type default)
			)
			(layer "F.SilkS")
		)
		(fp_line
			(start -0.12065 -0.305054)
			(end -0.12065 -0.2794)
			(stroke
				(width 0.1)
				(type default)
			)
			(layer "F.Fab")
		)
		(fp_line
			(start -0.67945 -0.305054)
			(end -0.12065 -0.305054)
			(stroke
				(width 0.1)
				(type default)
			)
			(layer "F.Fab")
		)
		(fp_line
			(start 0.67945 -0.3048)
			(end 0.67945 0.3048)
			(stroke
				(width 0.1)
				(type default)
			)
			(layer "F.Fab")
		)
		(fp_line
			(start 0.12065 -0.3048)
			(end 0.67945 -0.3048)
			(stroke
				(width 0.1)
				(type default)
			)
			(layer "F.Fab")
		)
		(fp_line
			(start 0.12065 -0.2794)
			(end 0.12065 -0.3048)
			(stroke
				(width 0.1)
				(type default)
			)
			(layer "F.Fab")
		)
		(fp_line
			(start -0.12065 -0.2794)
			(end 0.12065 -0.2794)
			(stroke
				(width 0.1)
				(type default)
			)
			(layer "F.Fab")
		)
		(fp_line
			(start 0.120396 0.2794)
			(end -0.12065 0.2794)
			(stroke
				(width 0.1)
				(type default)
			)
			(layer "F.Fab")
		)
		(fp_line
			(start -0.12065 0.2794)
			(end -0.12065 0.3048)
			(stroke
				(width 0.1)
				(type default)
			)
			(layer "F.Fab")
		)
		(fp_line
			(start 0.67945 0.3048)
			(end 0.120396 0.3048)
			(stroke
				(width 0.1)
				(type default)
			)
			(layer "F.Fab")
		)
		(fp_line
			(start 0.120396 0.3048)
			(end 0.120396 0.2794)
			(stroke
				(width 0.1)
				(type default)
			)
			(layer "F.Fab")
		)
		(fp_line
			(start -0.12065 0.3048)
			(end -0.67945 0.3048)
			(stroke
				(width 0.1)
				(type default)
			)
			(layer "F.Fab")
		)
		(fp_line
			(start -0.67945 0.3048)
			(end -0.67945 -0.305054)
			(stroke
				(width 0.1)
				(type default)
			)
			(layer "F.Fab")
		)
		(pad "1" smd circle
			(at -0.40005 0 90)
			(size 0 0)
			(layers "F.Cu" "F.Mask" "F.Paste")
			(net "P3V3_AUX")
		)
		(pad "2" smd circle
			(at 0.40005 0 90)
			(size 0 0)
			(layers "F.Cu" "F.Mask" "F.Paste")
			(net "USB_HUB_OVCUR3")
		)
	)
	(footprint ""
		(layer "F.Cu")
		(at 392.84021 -402.371052 -90)
		(property "Reference" "C949"
			(at 0 0 270)
			(layer "F.SilkS")
			(hide yes)
			(effects
				(font
					(size 1.27 1.27)
				)
			)
		)
		(property "Value" ""
			(at 0 0 270)
			(layer "F.Fab")
			(effects
				(font
					(size 1.27 1.27)
				)
			)
		)
		(duplicate_pad_numbers_are_jumpers no)
		(fp_line
			(start -0.299974 0.150114)
			(end -0.299974 -0.150114)
			(stroke
				(width 0.1)
				(type default)
			)
			(layer "F.Fab")
		)
		(fp_line
			(start 0.299974 0.150114)
			(end -0.299974 0.150114)
			(stroke
				(width 0.1)
				(type default)
			)
			(layer "F.Fab")
		)
		(fp_line
			(start -0.299974 -0.150114)
			(end 0.299974 -0.150114)
			(stroke
				(width 0.1)
				(type default)
			)
			(layer "F.Fab")
		)
		(fp_line
			(start 0.299974 -0.150114)
			(end 0.299974 0.150114)
			(stroke
				(width 0.1)
				(type default)
			)
			(layer "F.Fab")
		)
		(pad "1" smd rect
			(at -0.2667 0 270)
			(size 0.3048 0.381)
			(layers "F.Cu" "F.Mask" "F.Paste")
			(net "P5E_CPU0_PE2_TX_C_DP<8>")
		)
		(pad "2" smd rect
			(at 0.2667 0 270)
			(size 0.3048 0.381)
			(layers "F.Cu" "F.Mask" "F.Paste")
			(net "P5E_CPU0_PE2_TX_DP<8>")
		)
	)
	(footprint ""
		(layer "F.Cu")
		(at 439.295032 -23.839678)
		(property "Reference" "PR3843"
			(at 0 0 0)
			(layer "F.SilkS")
			(hide yes)
			(effects
				(font
					(size 1.27 1.27)
				)
			)
		)
		(property "Value" ""
			(at 0 0 0)
			(layer "F.Fab")
			(effects
				(font
					(size 1.27 1.27)
				)
			)
		)
		(duplicate_pad_numbers_are_jumpers no)
		(fp_line
			(start -1.2954 -0.5842)
			(end 1.2954 -0.5842)
			(stroke
				(width 0.1524)
				(type default)
			)
			(layer "F.SilkS")
		)
		(fp_line
			(start -1.2954 0.5842)
			(end -1.2954 -0.5842)
			(stroke
				(width 0.1524)
				(type default)
			)
			(layer "F.SilkS")
		)
		(fp_line
			(start 1.2954 -0.5842)
			(end 1.2954 0.5842)
			(stroke
				(width 0.1524)
				(type default)
			)
			(layer "F.SilkS")
		)
		(fp_line
			(start 1.2954 0.5842)
			(end -1.2954 0.5842)
			(stroke
				(width 0.1524)
				(type default)
			)
			(layer "F.SilkS")
		)
		(fp_line
			(start -1.1938 -0.406654)
			(end -0.8636 -0.406654)
			(stroke
				(width 0.1)
				(type default)
			)
			(layer "F.Fab")
		)
		(fp_line
			(start -1.1938 0.4064)
			(end -1.1938 -0.406654)
			(stroke
				(width 0.1)
				(type default)
			)
			(layer "F.Fab")
		)
		(fp_line
			(start -0.8636 -0.4572)
			(end 0.8636 -0.4572)
			(stroke
				(width 0.1)
				(type default)
			)
			(layer "F.Fab")
		)
		(fp_line
			(start -0.8636 -0.406654)
			(end -0.8636 -0.4572)
			(stroke
				(width 0.1)
				(type default)
			)
			(layer "F.Fab")
		)
		(fp_line
			(start -0.8636 0.4064)
			(end -1.1938 0.4064)
			(stroke
				(width 0.1)
				(type default)
			)
			(layer "F.Fab")
		)
		(fp_line
			(start -0.8636 0.4318)
			(end -0.8636 0.4064)
			(stroke
				(width 0.1)
				(type default)
			)
			(layer "F.Fab")
		)
		(fp_line
			(start -0.8636 0.4572)
			(end -0.8636 0.4318)
			(stroke
				(width 0.1)
				(type default)
			)
			(layer "F.Fab")
		)
		(fp_line
			(start 0.8636 -0.4572)
			(end 0.8636 -0.406654)
			(stroke
				(width 0.1)
				(type default)
			)
			(layer "F.Fab")
		)
		(fp_line
			(start 0.8636 -0.406654)
			(end 1.1938 -0.406654)
			(stroke
				(width 0.1)
				(type default)
			)
			(layer "F.Fab")
		)
		(fp_line
			(start 0.8636 0.4064)
			(end 0.8636 0.4572)
			(stroke
				(width 0.1)
				(type default)
			)
			(layer "F.Fab")
		)
		(fp_line
			(start 0.8636 0.4572)
			(end -0.8636 0.4572)
			(stroke
				(width 0.1)
				(type default)
			)
			(layer "F.Fab")
		)
		(fp_line
			(start 1.1938 -0.406654)
			(end 1.1938 0.4064)
			(stroke
				(width 0.1)
				(type default)
			)
			(layer "F.Fab")
		)
		(fp_line
			(start 1.1938 0.4064)
			(end 0.8636 0.4064)
			(stroke
				(width 0.1)
				(type default)
			)
			(layer "F.Fab")
		)
		(pad "1" smd rect
			(at -0.7366 0 270)
			(size 0.7112 0.8128)
			(layers "F.Cu" "F.Mask" "F.Paste")
			(net "P12V_AUX")
		)
		(pad "2" smd rect
			(at 0.7366 0 270)
			(size 0.7112 0.8128)
			(layers "F.Cu" "F.Mask" "F.Paste")
			(net "P12V_OCP_AVIN_PD_1")
		)
	)
	(footprint ""
		(layer "F.Cu")
		(at 365.46663 -258.726686 90)
		(property "Reference" "C972"
			(at 0 0 90)
			(layer "F.SilkS")
			(hide yes)
			(effects
				(font
					(size 1.27 1.27)
				)
			)
		)
		(property "Value" ""
			(at 0 0 90)
			(layer "F.Fab")
			(effects
				(font
					(size 1.27 1.27)
				)
			)
		)
		(duplicate_pad_numbers_are_jumpers no)
		(fp_line
			(start 0.7874 -0.4064)
			(end 0.7874 0.4064)
			(stroke
				(width 0.1524)
				(type default)
			)
			(layer "F.SilkS")
		)
		(fp_line
			(start -0.7874 -0.4064)
			(end 0.7874 -0.4064)
			(stroke
				(width 0.1524)
				(type default)
			)
			(layer "F.SilkS")
		)
		(fp_line
			(start 0.7874 0.4064)
			(end -0.7874 0.4064)
			(stroke
				(width 0.1524)
				(type default)
			)
			(layer "F.SilkS")
		)
		(fp_line
			(start -0.7874 0.4064)
			(end -0.7874 -0.4064)
			(stroke
				(width 0.1524)
				(type default)
			)
			(layer "F.SilkS")
		)
		(fp_line
			(start -0.12065 -0.305054)
			(end -0.12065 -0.2794)
			(stroke
				(width 0.1)
				(type default)
			)
			(layer "F.Fab")
		)
		(fp_line
			(start -0.67945 -0.305054)
			(end -0.12065 -0.305054)
			(stroke
				(width 0.1)
				(type default)
			)
			(layer "F.Fab")
		)
		(fp_line
			(start 0.67945 -0.3048)
			(end 0.67945 0.3048)
			(stroke
				(width 0.1)
				(type default)
			)
			(layer "F.Fab")
		)
		(fp_line
			(start 0.12065 -0.3048)
			(end 0.67945 -0.3048)
			(stroke
				(width 0.1)
				(type default)
			)
			(layer "F.Fab")
		)
		(fp_line
			(start 0.12065 -0.2794)
			(end 0.12065 -0.3048)
			(stroke
				(width 0.1)
				(type default)
			)
			(layer "F.Fab")
		)
		(fp_line
			(start -0.12065 -0.2794)
			(end 0.12065 -0.2794)
			(stroke
				(width 0.1)
				(type default)
			)
			(layer "F.Fab")
		)
		(fp_line
			(start 0.120396 0.2794)
			(end -0.12065 0.2794)
			(stroke
				(width 0.1)
				(type default)
			)
			(layer "F.Fab")
		)
		(fp_line
			(start -0.12065 0.2794)
			(end -0.12065 0.3048)
			(stroke
				(width 0.1)
				(type default)
			)
			(layer "F.Fab")
		)
		(fp_line
			(start 0.67945 0.3048)
			(end 0.120396 0.3048)
			(stroke
				(width 0.1)
				(type default)
			)
			(layer "F.Fab")
		)
		(fp_line
			(start 0.120396 0.3048)
			(end 0.120396 0.2794)
			(stroke
				(width 0.1)
				(type default)
			)
			(layer "F.Fab")
		)
		(fp_line
			(start -0.12065 0.3048)
			(end -0.67945 0.3048)
			(stroke
				(width 0.1)
				(type default)
			)
			(layer "F.Fab")
		)
		(fp_line
			(start -0.67945 0.3048)
			(end -0.67945 -0.305054)
			(stroke
				(width 0.1)
				(type default)
			)
			(layer "F.Fab")
		)
		(pad "1" smd circle
			(at -0.40005 0 90)
			(size 0 0)
			(layers "F.Cu" "F.Mask" "F.Paste")
			(net "PVCCIN_CPU0")
		)
		(pad "2" smd circle
			(at 0.40005 0 90)
			(size 0 0)
			(layers "F.Cu" "F.Mask" "F.Paste")
			(net "GND")
		)
	)
)
